(kicad_pcb
	(version 20260206)
	(generator "pcbnew")
	(generator_version "10.0")
	(general
		(thickness 1.6)
		(legacy_teardrops no)
	)
	(paper "A4")
	(title_block
		(title "04192023_DAF0TMB3IC0_F0TG_MB_C_brd_V02_OCP.brd")
		(comment 1 "Grand Teton / footprint 3955 of 8354 (U25), pads 1314-1426 of 6102")
	)
	(layers
		(0 "F.Cu" signal "TOP")
		(4 "In1.Cu" signal "GND")
		(6 "In2.Cu" signal "IN1")
		(8 "In3.Cu" signal "GND1")
		(10 "In4.Cu" signal "IN2")
		(12 "In5.Cu" signal "GND2")
		(14 "In6.Cu" signal "IN3")
		(16 "In7.Cu" signal "GND3")
		(18 "In8.Cu" signal "VCC")
		(20 "In9.Cu" signal "VCC1")
		(22 "In10.Cu" signal "GND4")
		(24 "In11.Cu" signal "IN4")
		(26 "In12.Cu" signal "GND5")
		(28 "In13.Cu" signal "IN5")
		(30 "In14.Cu" signal "GND6")
		(32 "In15.Cu" signal "IN6")
		(34 "In16.Cu" signal "GND7")
		(2 "B.Cu" signal "BOTTOM")
		(9 "F.Adhes" user "F.Adhesive")
		(11 "B.Adhes" user "B.Adhesive")
		(13 "F.Paste" user "Package Geometry/Pastemask Top")
		(15 "B.Paste" user "Package Geometry/Pastemask Bottom")
		(5 "F.SilkS" user "Ref Des/Silkscreen Top")
		(7 "B.SilkS" user "Ref Des/Silkscreen Bottom")
		(1 "F.Mask" user "Board Geometry/Soldermask Top")
		(3 "B.Mask" user "Board Geometry/Soldermask Bottom")
		(17 "Dwgs.User" user "User.Drawings")
		(19 "Cmts.User" user "User.Comments")
		(21 "Eco1.User" user "User.Eco1")
		(23 "Eco2.User" user "User.Eco2")
		(25 "Edge.Cuts" user "Board Geometry/Outline")
		(27 "Margin" user)
		(31 "F.CrtYd" user "Package Geometry/Place Bound Top")
		(29 "B.CrtYd" user "Package Geometry/Place Bound Bottom")
		(35 "F.Fab" user "Ref Des/Assembly Top")
		(33 "B.Fab" user "Ref Des/Assembly Bottom")
	)
	(footprint ""
		(layer "F.Cu")
		(at 359.867962 -258.880102 180)
		(property "Reference" "U25"
			(at -45.78477 -62.086744 0)
			(unlocked yes)
			(layer "F.SilkS")
			(effects
				(font
					(size 0.7874 0.5842)
					(thickness 0.1524)
				)
			)
		)
		(property "Value" ""
			(at 0 0 180)
			(layer "F.Fab")
			(effects
				(font
					(size 1.27 1.27)
				)
			)
		)
		(duplicate_pad_numbers_are_jumpers no)
		(pad "AV29" smd circle
			(at -8.310118 -6.839966 180)
			(size 0.450088 0.450088)
			(layers "F.Cu" "F.Mask" "F.Paste")
			(net "GND")
		)
		(pad "AV30" smd circle
			(at -7.370064 -6.839966 180)
			(size 0.450088 0.450088)
			(layers "F.Cu" "F.Mask" "F.Paste")
			(net "PVDDCR_SOC_P0")
		)
		(pad "AV31" smd circle
			(at -6.43001 -6.839966 180)
			(size 0.450088 0.450088)
			(layers "F.Cu" "F.Mask" "F.Paste")
			(net "GND")
		)
		(pad "AV32" smd circle
			(at -5.489956 -6.839966 180)
			(size 0.450088 0.450088)
			(layers "F.Cu" "F.Mask" "F.Paste")
			(net "PVDDCR_SOC_P0")
		)
		(pad "AV33" smd circle
			(at -4.549902 -6.839966 180)
			(size 0.450088 0.450088)
			(layers "F.Cu" "F.Mask" "F.Paste")
			(net "GND")
		)
		(pad "AV34" smd circle
			(at -3.610102 -6.839966 180)
			(size 0.450088 0.450088)
			(layers "F.Cu" "F.Mask" "F.Paste")
			(net "PVDDCR_SOC_P0")
		)
		(pad "AV35" smd circle
			(at -2.670048 -6.839966 180)
			(size 0.450088 0.450088)
			(layers "F.Cu" "F.Mask" "F.Paste")
			(net "GND")
		)
		(pad "AV36" smd circle
			(at -1.729994 -6.839966 180)
			(size 0.450088 0.450088)
			(layers "F.Cu" "F.Mask" "F.Paste")
			(net "PVDDCR_SOC_P0")
		)
		(pad "AV37" smd circle
			(at -0.78994 -6.839966 180)
			(size 0.450088 0.450088)
			(layers "F.Cu" "F.Mask" "F.Paste")
			(net "GND")
		)
		(pad "AV39" smd circle
			(at 1.089914 -6.839966 180)
			(size 0.450088 0.450088)
			(layers "F.Cu" "F.Mask" "F.Paste")
			(net "PVDDCR_SOC_P0")
		)
		(pad "AV40" smd circle
			(at 2.029968 -6.839966 180)
			(size 0.450088 0.450088)
			(layers "F.Cu" "F.Mask" "F.Paste")
			(net "GND")
		)
		(pad "AV41" smd circle
			(at 2.970022 -6.839966 180)
			(size 0.450088 0.450088)
			(layers "F.Cu" "F.Mask" "F.Paste")
			(net "PVDDCR_SOC_P0")
		)
		(pad "AV42" smd circle
			(at 3.910076 -6.839966 180)
			(size 0.450088 0.450088)
			(layers "F.Cu" "F.Mask" "F.Paste")
			(net "GND")
		)
		(pad "AV43" smd circle
			(at 4.849876 -6.839966 180)
			(size 0.450088 0.450088)
			(layers "F.Cu" "F.Mask" "F.Paste")
			(net "PVDDCR_SOC_P0")
		)
		(pad "AV44" smd circle
			(at 5.78993 -6.839966 180)
			(size 0.450088 0.450088)
			(layers "F.Cu" "F.Mask" "F.Paste")
			(net "GND")
		)
		(pad "AV45" smd circle
			(at 6.729984 -6.839966 180)
			(size 0.450088 0.450088)
			(layers "F.Cu" "F.Mask" "F.Paste")
			(net "PVDDCR_SOC_P0")
		)
		(pad "AV46" smd circle
			(at 7.670038 -6.839966 180)
			(size 0.450088 0.450088)
			(layers "F.Cu" "F.Mask" "F.Paste")
			(net "GND")
		)
		(pad "AV47" smd circle
			(at 8.610092 -6.839966 180)
			(size 0.450088 0.450088)
			(layers "F.Cu" "F.Mask" "F.Paste")
			(net "PVDDCR_SOC_P0")
		)
		(pad "AV48" smd circle
			(at 9.549892 -6.839966 180)
			(size 0.450088 0.450088)
			(layers "F.Cu" "F.Mask" "F.Paste")
			(net "GND")
		)
		(pad "AV49" smd circle
			(at 10.489946 -6.839966 180)
			(size 0.450088 0.450088)
			(layers "F.Cu" "F.Mask" "F.Paste")
			(net "PVDD18_S5_P0")
		)
		(pad "AV50" smd circle
			(at 11.43 -6.839966 180)
			(size 0.450088 0.450088)
			(layers "F.Cu" "F.Mask" "F.Paste")
			(net "GND")
		)
		(pad "AV51" smd circle
			(at 12.370054 -6.839966 180)
			(size 0.450088 0.450088)
			(layers "F.Cu" "F.Mask" "F.Paste")
			(net "PVDD18_S5_P0")
		)
		(pad "AV52" smd circle
			(at 13.310108 -6.839966 180)
			(size 0.450088 0.450088)
			(layers "F.Cu" "F.Mask" "F.Paste")
			(net "GND")
		)
		(pad "AV53" smd circle
			(at 14.249908 -6.839966 180)
			(size 0.450088 0.450088)
			(layers "F.Cu" "F.Mask" "F.Paste")
			(net "PVDD18_S5_P0")
		)
		(pad "AV54" smd circle
			(at 15.189962 -6.839966 180)
			(size 0.450088 0.450088)
			(layers "F.Cu" "F.Mask" "F.Paste")
			(net "GND")
		)
		(pad "AV55" smd circle
			(at 16.130016 -6.839966 180)
			(size 0.450088 0.450088)
			(layers "F.Cu" "F.Mask" "F.Paste")
			(net "Net_1806")
		)
		(pad "AV56" smd circle
			(at 17.07007 -6.839966 180)
			(size 0.450088 0.450088)
			(layers "F.Cu" "F.Mask" "F.Paste")
			(net "M_C_CPU0_SA_CS_N<0>")
		)
		(pad "AV57" smd circle
			(at 18.010124 -6.839966 180)
			(size 0.450088 0.450088)
			(layers "F.Cu" "F.Mask" "F.Paste")
			(net "PVDDIO_P0")
		)
		(pad "AV58" smd circle
			(at 18.949924 -6.839966 180)
			(size 0.450088 0.450088)
			(layers "F.Cu" "F.Mask" "F.Paste")
			(net "Net_1814")
		)
		(pad "AV59" smd circle
			(at 19.889978 -6.839966 180)
			(size 0.450088 0.450088)
			(layers "F.Cu" "F.Mask" "F.Paste")
			(net "GND")
		)
		(pad "AV60" smd circle
			(at 20.830032 -6.839966 180)
			(size 0.450088 0.450088)
			(layers "F.Cu" "F.Mask" "F.Paste")
			(net "M_D_CPU0_SA_CS_N<0>")
		)
		(pad "AV61" smd circle
			(at 21.770086 -6.839966 180)
			(size 0.450088 0.450088)
			(layers "F.Cu" "F.Mask" "F.Paste")
			(net "GND")
		)
		(pad "AV62" smd circle
			(at 22.709886 -6.839966 180)
			(size 0.450088 0.450088)
			(layers "F.Cu" "F.Mask" "F.Paste")
			(net "Net_1798")
		)
		(pad "AV63" smd circle
			(at 23.64994 -6.839966 180)
			(size 0.450088 0.450088)
			(layers "F.Cu" "F.Mask" "F.Paste")
			(net "M_B_CPU0_SA_CS_N<0>")
		)
		(pad "AV64" smd circle
			(at 24.589994 -6.839966 180)
			(size 0.450088 0.450088)
			(layers "F.Cu" "F.Mask" "F.Paste")
			(net "PVDDIO_P0")
		)
		(pad "AV65" smd circle
			(at 25.530048 -6.839966 180)
			(size 0.450088 0.450088)
			(layers "F.Cu" "F.Mask" "F.Paste")
			(net "Net_1830")
		)
		(pad "AV66" smd circle
			(at 26.470102 -6.839966 180)
			(size 0.450088 0.450088)
			(layers "F.Cu" "F.Mask" "F.Paste")
			(net "GND")
		)
		(pad "AV67" smd circle
			(at 27.409902 -6.839966 180)
			(size 0.450088 0.450088)
			(layers "F.Cu" "F.Mask" "F.Paste")
			(net "M_F_CPU0_SA_CS_N<0>")
		)
		(pad "AV68" smd circle
			(at 28.349956 -6.839966 180)
			(size 0.450088 0.450088)
			(layers "F.Cu" "F.Mask" "F.Paste")
			(net "GND")
		)
		(pad "AV69" smd circle
			(at 29.29001 -6.839966 180)
			(size 0.450088 0.450088)
			(layers "F.Cu" "F.Mask" "F.Paste")
			(net "Net_1822")
		)
		(pad "AV70" smd circle
			(at 30.230064 -6.839966 180)
			(size 0.450088 0.450088)
			(layers "F.Cu" "F.Mask" "F.Paste")
			(net "M_E_CPU0_SA_CS_N<0>")
		)
		(pad "AV71" smd circle
			(at 31.170118 -6.839966 180)
			(size 0.450088 0.450088)
			(layers "F.Cu" "F.Mask" "F.Paste")
			(net "PVDDIO_P0")
		)
		(pad "AV72" smd circle
			(at 32.109918 -6.839966 180)
			(size 0.450088 0.450088)
			(layers "F.Cu" "F.Mask" "F.Paste")
			(net "Net_1790")
		)
		(pad "AV73" smd circle
			(at 33.049972 -6.839966 180)
			(size 0.450088 0.450088)
			(layers "F.Cu" "F.Mask" "F.Paste")
			(net "GND")
		)
		(pad "AV74" smd circle
			(at 33.990026 -6.839966 180)
			(size 0.450088 0.450088)
			(layers "F.Cu" "F.Mask" "F.Paste")
			(net "M_A_CPU0_SA_CS_N<0>")
		)
		(pad "AW1" smd circle
			(at -34.159952 -6.02996 180)
			(size 0.450088 0.450088)
			(layers "F.Cu" "F.Mask" "F.Paste")
			(net "GND")
		)
		(pad "AW2" smd circle
			(at -33.219898 -6.02996 180)
			(size 0.450088 0.450088)
			(layers "F.Cu" "F.Mask" "F.Paste")
			(net "M_G_CPU0_SA_CA<0>")
		)
		(pad "AW3" smd circle
			(at -32.280098 -6.02996 180)
			(size 0.450088 0.450088)
			(layers "F.Cu" "F.Mask" "F.Paste")
			(net "Net_1838")
		)
		(pad "AW4" smd circle
			(at -31.340044 -6.02996 180)
			(size 0.450088 0.450088)
			(layers "F.Cu" "F.Mask" "F.Paste")
			(net "GND")
		)
		(pad "AW5" smd circle
			(at -30.39999 -6.02996 180)
			(size 0.450088 0.450088)
			(layers "F.Cu" "F.Mask" "F.Paste")
			(net "M_K_CPU0_SA_CA<0>")
		)
		(pad "AW6" smd circle
			(at -29.459936 -6.02996 180)
			(size 0.450088 0.450088)
			(layers "F.Cu" "F.Mask" "F.Paste")
			(net "GND")
		)
		(pad "AW7" smd circle
			(at -28.519882 -6.02996 180)
			(size 0.450088 0.450088)
			(layers "F.Cu" "F.Mask" "F.Paste")
			(net "Net_1967")
		)
		(pad "AW8" smd circle
			(at -27.580082 -6.02996 180)
			(size 0.450088 0.450088)
			(layers "F.Cu" "F.Mask" "F.Paste")
			(net "GND")
		)
		(pad "AW9" smd circle
			(at -26.640028 -6.02996 180)
			(size 0.450088 0.450088)
			(layers "F.Cu" "F.Mask" "F.Paste")
			(net "M_L_CPU0_SA_CA<0>")
		)
		(pad "AW10" smd circle
			(at -25.699974 -6.02996 180)
			(size 0.450088 0.450088)
			(layers "F.Cu" "F.Mask" "F.Paste")
			(net "Net_1959")
		)
		(pad "AW11" smd circle
			(at -24.75992 -6.02996 180)
			(size 0.450088 0.450088)
			(layers "F.Cu" "F.Mask" "F.Paste")
			(net "GND")
		)
		(pad "AW12" smd circle
			(at -23.82012 -6.02996 180)
			(size 0.450088 0.450088)
			(layers "F.Cu" "F.Mask" "F.Paste")
			(net "M_H_CPU0_SA_CA<0>")
		)
		(pad "AW13" smd circle
			(at -22.880066 -6.02996 180)
			(size 0.450088 0.450088)
			(layers "F.Cu" "F.Mask" "F.Paste")
			(net "GND")
		)
		(pad "AW14" smd circle
			(at -21.940012 -6.02996 180)
			(size 0.450088 0.450088)
			(layers "F.Cu" "F.Mask" "F.Paste")
			(net "Net_1846")
		)
		(pad "AW15" smd circle
			(at -20.999958 -6.02996 180)
			(size 0.450088 0.450088)
			(layers "F.Cu" "F.Mask" "F.Paste")
			(net "GND")
		)
		(pad "AW16" smd circle
			(at -20.059904 -6.02996 180)
			(size 0.450088 0.450088)
			(layers "F.Cu" "F.Mask" "F.Paste")
			(net "M_J_CPU0_SA_CA<0>")
		)
		(pad "AW17" smd circle
			(at -19.120104 -6.02996 180)
			(size 0.450088 0.450088)
			(layers "F.Cu" "F.Mask" "F.Paste")
			(net "Net_1862")
		)
		(pad "AW18" smd circle
			(at -18.18005 -6.02996 180)
			(size 0.450088 0.450088)
			(layers "F.Cu" "F.Mask" "F.Paste")
			(net "GND")
		)
		(pad "AW19" smd circle
			(at -17.239996 -6.02996 180)
			(size 0.450088 0.450088)
			(layers "F.Cu" "F.Mask" "F.Paste")
			(net "M_I_CPU0_SA_CA<0>")
		)
		(pad "AW20" smd circle
			(at -16.299942 -6.02996 180)
			(size 0.450088 0.450088)
			(layers "F.Cu" "F.Mask" "F.Paste")
			(net "GND")
		)
		(pad "AW21" smd circle
			(at -15.359888 -6.02996 180)
			(size 0.450088 0.450088)
			(layers "F.Cu" "F.Mask" "F.Paste")
			(net "Net_1854")
		)
		(pad "AW22" smd circle
			(at -14.420088 -6.02996 180)
			(size 0.450088 0.450088)
			(layers "F.Cu" "F.Mask" "F.Paste")
			(net "GND")
		)
		(pad "AW23" smd circle
			(at -13.480034 -6.02996 180)
			(size 0.450088 0.450088)
			(layers "F.Cu" "F.Mask" "F.Paste")
			(net "PVDDCR_SOC_P0")
		)
		(pad "AW24" smd circle
			(at -12.53998 -6.02996 180)
			(size 0.450088 0.450088)
			(layers "F.Cu" "F.Mask" "F.Paste")
			(net "GND")
		)
		(pad "AW25" smd circle
			(at -11.599926 -6.02996 180)
			(size 0.450088 0.450088)
			(layers "F.Cu" "F.Mask" "F.Paste")
			(net "PVDDCR_SOC_P0")
		)
		(pad "AW26" smd circle
			(at -10.659872 -6.02996 180)
			(size 0.450088 0.450088)
			(layers "F.Cu" "F.Mask" "F.Paste")
			(net "GND")
		)
		(pad "AW27" smd circle
			(at -9.720072 -6.02996 180)
			(size 0.450088 0.450088)
			(layers "F.Cu" "F.Mask" "F.Paste")
			(net "PVDDCR_SOC_P0")
		)
		(pad "AW28" smd circle
			(at -8.780018 -6.02996 180)
			(size 0.450088 0.450088)
			(layers "F.Cu" "F.Mask" "F.Paste")
			(net "GND")
		)
		(pad "AW48" smd circle
			(at 9.079992 -6.02996 180)
			(size 0.450088 0.450088)
			(layers "F.Cu" "F.Mask" "F.Paste")
			(net "PVDDCR_SOC_P0")
		)
		(pad "AW49" smd circle
			(at 10.020046 -6.02996 180)
			(size 0.450088 0.450088)
			(layers "F.Cu" "F.Mask" "F.Paste")
			(net "GND")
		)
		(pad "AW50" smd circle
			(at 10.9601 -6.02996 180)
			(size 0.450088 0.450088)
			(layers "F.Cu" "F.Mask" "F.Paste")
			(net "PVDD18_S5_P0")
		)
		(pad "AW51" smd circle
			(at 11.8999 -6.02996 180)
			(size 0.450088 0.450088)
			(layers "F.Cu" "F.Mask" "F.Paste")
			(net "GND")
		)
		(pad "AW52" smd circle
			(at 12.839954 -6.02996 180)
			(size 0.450088 0.450088)
			(layers "F.Cu" "F.Mask" "F.Paste")
			(net "PVDD18_S5_P0")
		)
		(pad "AW53" smd circle
			(at 13.780008 -6.02996 180)
			(size 0.450088 0.450088)
			(layers "F.Cu" "F.Mask" "F.Paste")
			(net "GND")
		)
		(pad "AW54" smd circle
			(at 14.720062 -6.02996 180)
			(size 0.450088 0.450088)
			(layers "F.Cu" "F.Mask" "F.Paste")
			(net "PVDD18_S5_P0")
		)
		(pad "AW55" smd circle
			(at 15.660116 -6.02996 180)
			(size 0.450088 0.450088)
			(layers "F.Cu" "F.Mask" "F.Paste")
			(net "M_C_CPU0_SA_CS_N<1>")
		)
		(pad "AW56" smd circle
			(at 16.599916 -6.02996 180)
			(size 0.450088 0.450088)
			(layers "F.Cu" "F.Mask" "F.Paste")
			(net "GND")
		)
		(pad "AW57" smd circle
			(at 17.53997 -6.02996 180)
			(size 0.450088 0.450088)
			(layers "F.Cu" "F.Mask" "F.Paste")
			(net "M_C_CPU0_SA_CA<0>")
		)
		(pad "AW58" smd circle
			(at 18.480024 -6.02996 180)
			(size 0.450088 0.450088)
			(layers "F.Cu" "F.Mask" "F.Paste")
			(net "GND")
		)
		(pad "AW59" smd circle
			(at 19.420078 -6.02996 180)
			(size 0.450088 0.450088)
			(layers "F.Cu" "F.Mask" "F.Paste")
			(net "M_D_CPU0_SA_CS_N<1>")
		)
		(pad "AW60" smd circle
			(at 20.359878 -6.02996 180)
			(size 0.450088 0.450088)
			(layers "F.Cu" "F.Mask" "F.Paste")
			(net "M_D_CPU0_SA_CA<0>")
		)
		(pad "AW61" smd circle
			(at 21.299932 -6.02996 180)
			(size 0.450088 0.450088)
			(layers "F.Cu" "F.Mask" "F.Paste")
			(net "GND")
		)
		(pad "AW62" smd circle
			(at 22.239986 -6.02996 180)
			(size 0.450088 0.450088)
			(layers "F.Cu" "F.Mask" "F.Paste")
			(net "M_B_CPU0_SA_CS_N<1>")
		)
		(pad "AW63" smd circle
			(at 23.18004 -6.02996 180)
			(size 0.450088 0.450088)
			(layers "F.Cu" "F.Mask" "F.Paste")
			(net "GND")
		)
		(pad "AW64" smd circle
			(at 24.120094 -6.02996 180)
			(size 0.450088 0.450088)
			(layers "F.Cu" "F.Mask" "F.Paste")
			(net "M_B_CPU0_SA_CA<0>")
		)
		(pad "AW65" smd circle
			(at 25.059894 -6.02996 180)
			(size 0.450088 0.450088)
			(layers "F.Cu" "F.Mask" "F.Paste")
			(net "GND")
		)
		(pad "AW66" smd circle
			(at 25.999948 -6.02996 180)
			(size 0.450088 0.450088)
			(layers "F.Cu" "F.Mask" "F.Paste")
			(net "M_F_CPU0_SA_CS_N<1>")
		)
		(pad "AW67" smd circle
			(at 26.940002 -6.02996 180)
			(size 0.450088 0.450088)
			(layers "F.Cu" "F.Mask" "F.Paste")
			(net "M_F_CPU0_SA_CA<0>")
		)
		(pad "AW68" smd circle
			(at 27.880056 -6.02996 180)
			(size 0.450088 0.450088)
			(layers "F.Cu" "F.Mask" "F.Paste")
			(net "GND")
		)
		(pad "AW69" smd circle
			(at 28.82011 -6.02996 180)
			(size 0.450088 0.450088)
			(layers "F.Cu" "F.Mask" "F.Paste")
			(net "M_E_CPU0_SA_CS_N<1>")
		)
		(pad "AW70" smd circle
			(at 29.75991 -6.02996 180)
			(size 0.450088 0.450088)
			(layers "F.Cu" "F.Mask" "F.Paste")
			(net "GND")
		)
		(pad "AW71" smd circle
			(at 30.699964 -6.02996 180)
			(size 0.450088 0.450088)
			(layers "F.Cu" "F.Mask" "F.Paste")
			(net "M_E_CPU0_SA_CA<0>")
		)
		(pad "AW72" smd circle
			(at 31.640018 -6.02996 180)
			(size 0.450088 0.450088)
			(layers "F.Cu" "F.Mask" "F.Paste")
			(net "GND")
		)
		(pad "AW73" smd circle
			(at 32.580072 -6.02996 180)
			(size 0.450088 0.450088)
			(layers "F.Cu" "F.Mask" "F.Paste")
			(net "M_A_CPU0_SA_CS_N<1>")
		)
		(pad "AW74" smd circle
			(at 33.519872 -6.02996 180)
			(size 0.450088 0.450088)
			(layers "F.Cu" "F.Mask" "F.Paste")
			(net "M_A_CPU0_SA_CA<0>")
		)
		(pad "AW75" smd circle
			(at 34.459926 -6.02996 180)
			(size 0.450088 0.450088)
			(layers "F.Cu" "F.Mask" "F.Paste")
			(net "GND")
		)
		(pad "AY2" smd circle
			(at -33.690052 -5.219954 180)
			(size 0.450088 0.450088)
			(layers "F.Cu" "F.Mask" "F.Paste")
			(net "M_G_CPU0_SA_CA<1>")
		)
		(pad "AY3" smd circle
			(at -32.749998 -5.219954 180)
			(size 0.450088 0.450088)
			(layers "F.Cu" "F.Mask" "F.Paste")
			(net "GND")
		)
		(pad "AY4" smd circle
			(at -31.809944 -5.219954 180)
			(size 0.450088 0.450088)
			(layers "F.Cu" "F.Mask" "F.Paste")
			(net "M_G_CPU0_SA_CA<2>")
		)
		(pad "AY5" smd circle
			(at -30.86989 -5.219954 180)
			(size 0.450088 0.450088)
			(layers "F.Cu" "F.Mask" "F.Paste")
			(net "GND")
		)
		(pad "AY6" smd circle
			(at -29.93009 -5.219954 180)
			(size 0.450088 0.450088)
			(layers "F.Cu" "F.Mask" "F.Paste")
			(net "M_K_CPU0_SA_CA<1>")
		)
		(pad "AY7" smd circle
			(at -28.990036 -5.219954 180)
			(size 0.450088 0.450088)
			(layers "F.Cu" "F.Mask" "F.Paste")
			(net "M_K_CPU0_SA_CA<2>")
		)
		(pad "AY8" smd circle
			(at -28.049982 -5.219954 180)
			(size 0.450088 0.450088)
			(layers "F.Cu" "F.Mask" "F.Paste")
			(net "GND")
		)
		(pad "AY9" smd circle
			(at -27.109928 -5.219954 180)
			(size 0.450088 0.450088)
			(layers "F.Cu" "F.Mask" "F.Paste")
			(net "M_L_CPU0_SA_CA<1>")
		)
		(pad "AY10" smd circle
			(at -26.170128 -5.219954 180)
			(size 0.450088 0.450088)
			(layers "F.Cu" "F.Mask" "F.Paste")
			(net "GND")
		)
		(pad "AY11" smd circle
			(at -25.230074 -5.219954 180)
			(size 0.450088 0.450088)
			(layers "F.Cu" "F.Mask" "F.Paste")
			(net "M_L_CPU0_SA_CA<2>")
		)
		(pad "AY12" smd circle
			(at -24.29002 -5.219954 180)
			(size 0.450088 0.450088)
			(layers "F.Cu" "F.Mask" "F.Paste")
			(net "GND")
		)
		(pad "AY13" smd circle
			(at -23.349966 -5.219954 180)
			(size 0.450088 0.450088)
			(layers "F.Cu" "F.Mask" "F.Paste")
			(net "M_H_CPU0_SA_CA<1>")
		)
	)
)
